# S9S_MB_2U (Grand Teton) — schematic netlist excerpt (pin names and nets, part order shuffled) for the footprints in the layout excerpt that follows; sources: Cadence DE-HDL packaged netlist, KiCad conversion of 03242023_DA0F0TMBIJ0_F0T_Motherboard_J_brd_V01_OCP.brd

C2357  Q_CAP  0.1UF 25V 10% X7R  pkg 0402  page 167 : A = P2E_BUF2_VDD ; B = GND
R2227  Q_RES  1K 1% CHIP  pkg 0402LF  page 306 : A = A_P12V_STBY_ADR_TRIGGER ; B = GND

(kicad_pcb
	(version 20260206)
	(generator "pcbnew")
	(generator_version "10.0")
	(general
		(thickness 1.6)
		(legacy_teardrops no)
	)
	(paper "A4")
	(title_block
		(title "03242023_DA0F0TMBIJ0_F0T_Motherboard_J_brd_V01_OCP.brd")
		(comment 1 "Grand Teton / footprints 1967-1968 of 6105")
	)
	(layers
		(0 "F.Cu" signal "TOP")
		(4 "In1.Cu" signal "GND")
		(6 "In2.Cu" signal "IN1")
		(8 "In3.Cu" signal "GND1")
		(10 "In4.Cu" signal "IN2")
		(12 "In5.Cu" signal "GND2")
		(14 "In6.Cu" signal "IN3")
		(16 "In7.Cu" signal "GND3")
		(18 "In8.Cu" signal "VCC")
		(20 "In9.Cu" signal "VCC1")
		(22 "In10.Cu" signal "GND4")
		(24 "In11.Cu" signal "IN4")
		(26 "In12.Cu" signal "GND5")
		(28 "In13.Cu" signal "IN5")
		(30 "In14.Cu" signal "GND6")
		(32 "In15.Cu" signal "IN6")
		(34 "In16.Cu" signal "GND7")
		(2 "B.Cu" signal "BOTTOM")
		(9 "F.Adhes" user "F.Adhesive")
		(11 "B.Adhes" user "B.Adhesive")
		(13 "F.Paste" user "Package Geometry/Pastemask Top")
		(15 "B.Paste" user "Package Geometry/Pastemask Bottom")
		(5 "F.SilkS" user "Ref Des/Silkscreen Top")
		(7 "B.SilkS" user "Ref Des/Silkscreen Bottom")
		(1 "F.Mask" user "Board Geometry/Soldermask Top")
		(3 "B.Mask" user "Board Geometry/Soldermask Bottom")
		(17 "Dwgs.User" user "User.Drawings")
		(19 "Cmts.User" user "User.Comments")
		(21 "Eco1.User" user "User.Eco1")
		(23 "Eco2.User" user "User.Eco2")
		(25 "Edge.Cuts" user "Board Geometry/Outline")
		(27 "Margin" user)
		(31 "F.CrtYd" user "Package Geometry/Place Bound Top")
		(29 "B.CrtYd" user "Package Geometry/Place Bound Bottom")
		(35 "F.Fab" user "Ref Des/Assembly Top")
		(33 "B.Fab" user "Ref Des/Assembly Bottom")
	)
	(footprint ""
		(layer "F.Cu")
		(at 210.566 -97.6376)
		(property "Reference" "R2227"
			(at 0 0 0)
			(layer "F.SilkS")
			(hide yes)
			(effects
				(font
					(size 1.27 1.27)
				)
			)
		)
		(property "Value" ""
			(at 0 0 0)
			(layer "F.Fab")
			(effects
				(font
					(size 1.27 1.27)
				)
			)
		)
		(duplicate_pad_numbers_are_jumpers no)
		(fp_line
			(start -0.7874 -0.4064)
			(end 0.7874 -0.4064)
			(stroke
				(width 0.1524)
				(type default)
			)
			(layer "F.SilkS")
		)
		(fp_line
			(start -0.7874 0.4064)
			(end -0.7874 -0.4064)
			(stroke
				(width 0.1524)
				(type default)
			)
			(layer "F.SilkS")
		)
		(fp_line
			(start 0.7874 -0.4064)
			(end 0.7874 0.4064)
			(stroke
				(width 0.1524)
				(type default)
			)
			(layer "F.SilkS")
		)
		(fp_line
			(start 0.7874 0.4064)
			(end -0.7874 0.4064)
			(stroke
				(width 0.1524)
				(type default)
			)
			(layer "F.SilkS")
		)
		(fp_line
			(start -0.67945 -0.305054)
			(end -0.12065 -0.305054)
			(stroke
				(width 0.1)
				(type default)
			)
			(layer "F.Fab")
		)
		(fp_line
			(start -0.67945 0.3048)
			(end -0.67945 -0.305054)
			(stroke
				(width 0.1)
				(type default)
			)
			(layer "F.Fab")
		)
		(fp_line
			(start -0.12065 -0.305054)
			(end -0.12065 -0.2794)
			(stroke
				(width 0.1)
				(type default)
			)
			(layer "F.Fab")
		)
		(fp_line
			(start -0.12065 -0.2794)
			(end 0.12065 -0.2794)
			(stroke
				(width 0.1)
				(type default)
			)
			(layer "F.Fab")
		)
		(fp_line
			(start -0.12065 0.2794)
			(end -0.12065 0.3048)
			(stroke
				(width 0.1)
				(type default)
			)
			(layer "F.Fab")
		)
		(fp_line
			(start -0.12065 0.3048)
			(end -0.67945 0.3048)
			(stroke
				(width 0.1)
				(type default)
			)
			(layer "F.Fab")
		)
		(fp_line
			(start 0.120396 0.2794)
			(end -0.12065 0.2794)
			(stroke
				(width 0.1)
				(type default)
			)
			(layer "F.Fab")
		)
		(fp_line
			(start 0.120396 0.3048)
			(end 0.120396 0.2794)
			(stroke
				(width 0.1)
				(type default)
			)
			(layer "F.Fab")
		)
		(fp_line
			(start 0.12065 -0.3048)
			(end 0.67945 -0.3048)
			(stroke
				(width 0.1)
				(type default)
			)
			(layer "F.Fab")
		)
		(fp_line
			(start 0.12065 -0.2794)
			(end 0.12065 -0.3048)
			(stroke
				(width 0.1)
				(type default)
			)
			(layer "F.Fab")
		)
		(fp_line
			(start 0.67945 -0.3048)
			(end 0.67945 0.3048)
			(stroke
				(width 0.1)
				(type default)
			)
			(layer "F.Fab")
		)
		(fp_line
			(start 0.67945 0.3048)
			(end 0.120396 0.3048)
			(stroke
				(width 0.1)
				(type default)
			)
			(layer "F.Fab")
		)
		(pad "1" smd circle
			(at -0.40005 0)
			(size 0 0)
			(layers "F.Cu" "F.Mask" "F.Paste")
			(net "A_P12V_STBY_ADR_TRIGGER")
		)
		(pad "2" smd circle
			(at 0.40005 0)
			(size 0 0)
			(layers "F.Cu" "F.Mask" "F.Paste")
			(net "GND")
		)
	)
	(footprint ""
		(layer "F.Cu")
		(at 40.27678 -387.35127 -90)
		(property "Reference" "C2357"
			(at 0 0 270)
			(layer "F.SilkS")
			(hide yes)
			(effects
				(font
					(size 1.27 1.27)
				)
			)
		)
		(property "Value" ""
			(at 0 0 270)
			(layer "F.Fab")
			(effects
				(font
					(size 1.27 1.27)
				)
			)
		)
		(duplicate_pad_numbers_are_jumpers no)
		(fp_line
			(start -0.7874 0.4064)
			(end -0.7874 -0.4064)
			(stroke
				(width 0.1524)
				(type default)
			)
			(layer "F.SilkS")
		)
		(fp_line
			(start 0.7874 0.4064)
			(end -0.7874 0.4064)
			(stroke
				(width 0.1524)
				(type default)
			)
			(layer "F.SilkS")
		)
		(fp_line
			(start -0.7874 -0.4064)
			(end 0.7874 -0.4064)
			(stroke
				(width 0.1524)
				(type default)
			)
			(layer "F.SilkS")
		)
		(fp_line
			(start 0.7874 -0.4064)
			(end 0.7874 0.4064)
			(stroke
				(width 0.1524)
				(type default)
			)
			(layer "F.SilkS")
		)
		(fp_line
			(start -0.67945 0.3048)
			(end -0.67945 -0.305054)
			(stroke
				(width 0.1)
				(type default)
			)
			(layer "F.Fab")
		)
		(fp_line
			(start -0.12065 0.3048)
			(end -0.67945 0.3048)
			(stroke
				(width 0.1)
				(type default)
			)
			(layer "F.Fab")
		)
		(fp_line
			(start 0.120396 0.3048)
			(end 0.120396 0.2794)
			(stroke
				(width 0.1)
				(type default)
			)
			(layer "F.Fab")
		)
		(fp_line
			(start 0.67945 0.3048)
			(end 0.120396 0.3048)
			(stroke
				(width 0.1)
				(type default)
			)
			(layer "F.Fab")
		)
		(fp_line
			(start -0.12065 0.2794)
			(end -0.12065 0.3048)
			(stroke
				(width 0.1)
				(type default)
			)
			(layer "F.Fab")
		)
		(fp_line
			(start 0.120396 0.2794)
			(end -0.12065 0.2794)
			(stroke
				(width 0.1)
				(type default)
			)
			(layer "F.Fab")
		)
		(fp_line
			(start -0.12065 -0.2794)
			(end 0.12065 -0.2794)
			(stroke
				(width 0.1)
				(type default)
			)
			(layer "F.Fab")
		)
		(fp_line
			(start 0.12065 -0.2794)
			(end 0.12065 -0.3048)
			(stroke
				(width 0.1)
				(type default)
			)
			(layer "F.Fab")
		)
		(fp_line
			(start 0.12065 -0.3048)
			(end 0.67945 -0.3048)
			(stroke
				(width 0.1)
				(type default)
			)
			(layer "F.Fab")
		)
		(fp_line
			(start 0.67945 -0.3048)
			(end 0.67945 0.3048)
			(stroke
				(width 0.1)
				(type default)
			)
			(layer "F.Fab")
		)
		(fp_line
			(start -0.67945 -0.305054)
			(end -0.12065 -0.305054)
			(stroke
				(width 0.1)
				(type default)
			)
			(layer "F.Fab")
		)
		(fp_line
			(start -0.12065 -0.305054)
			(end -0.12065 -0.2794)
			(stroke
				(width 0.1)
				(type default)
			)
			(layer "F.Fab")
		)
		(pad "1" smd circle
			(at -0.40005 0 270)
			(size 0 0)
			(layers "F.Cu" "F.Mask" "F.Paste")
			(net "P2E_BUF2_VDD")
		)
		(pad "2" smd circle
			(at 0.40005 0 270)
			(size 0 0)
			(layers "F.Cu" "F.Mask" "F.Paste")
			(net "GND")
		)
	)
)
